(kicad_pcb
	(version 20241229)
	(generator "pcbnew")
	(generator_version "9.0")
	(general
		(thickness 1.63)
		(legacy_teardrops no)
	)
	(paper "A4")
	(title_block
		(title "CM4 Baseboard")
		(date "2026-01-05")
		(rev "1.1.1")
		(company "Antmicro Ltd")
		(comment 1 "www.antmicro.com")
		(comment 9 "footprints 354-356 of 506")
	)
	(layers
		(0 "F.Cu" signal)
		(4 "In1.Cu" power)
		(6 "In2.Cu" power)
		(8 "In3.Cu" signal)
		(10 "In4.Cu" signal)
		(2 "B.Cu" signal)
		(9 "F.Adhes" user "F.Adhesive")
		(11 "B.Adhes" user "B.Adhesive")
		(13 "F.Paste" user)
		(15 "B.Paste" user)
		(5 "F.SilkS" user "F.Silkscreen")
		(7 "B.SilkS" user "B.Silkscreen")
		(1 "F.Mask" user)
		(3 "B.Mask" user)
		(17 "Dwgs.User" user "User.Drawings")
		(19 "Cmts.User" user "User.Comments")
		(21 "Eco1.User" user "User.Eco1")
		(23 "Eco2.User" user "User.Eco2")
		(25 "Edge.Cuts" user)
		(27 "Margin" user)
		(31 "F.CrtYd" user "F.Courtyard")
		(29 "B.CrtYd" user "B.Courtyard")
		(35 "F.Fab" user)
		(33 "B.Fab" user)
	)
	(footprint "antmicro-footprints:R_0402_1005Metric"
		(layer "B.Cu")
		(at 54.352962 153.2565 180)
		(descr "Resistor SMD 0402")
		(tags "resistor SMD 0402")
		(property "Reference" "R314"
			(at -0.555 0.415 0)
			(layer "B.SilkS")
			(effects
				(font
					(size 0.7 0.7)
					(thickness 0.15)
				)
				(justify left bottom mirror)
			)
		)
		(property "Value" "R_10k_0402"
			(at -1.011843 -1.772047 0)
			(layer "B.Fab")
			(effects
				(font
					(size 0.7 0.7)
					(thickness 0.15)
				)
				(justify left bottom mirror)
			)
		)
		(property "Datasheet" "https://www.bourns.com/docs/product-datasheets/cr.pdf"
			(at 0 0 180)
			(layer "B.Fab")
			(hide yes)
			(effects
				(font
					(size 1.27 1.27)
					(thickness 0.15)
				)
			)
		)
		(property "Manufacturer" "Bourns"
			(at 0 0 180)
			(unlocked yes)
			(layer "B.Fab")
			(hide yes)
			(effects
				(font
					(size 1 1)
					(thickness 0.15)
				)
				(justify mirror)
			)
		)
		(property "MPN" "CR0402-FX-1002GLF"
			(at 0 0 180)
			(unlocked yes)
			(layer "B.Fab")
			(hide yes)
			(effects
				(font
					(size 1 1)
					(thickness 0.15)
				)
				(justify mirror)
			)
		)
		(property "Val" "10k"
			(at 0 0 180)
			(unlocked yes)
			(layer "B.Fab")
			(hide yes)
			(effects
				(font
					(size 1 1)
					(thickness 0.15)
				)
				(justify mirror)
			)
		)
		(property "License" "Apache-2.0"
			(at 0 0 180)
			(unlocked yes)
			(layer "B.Fab")
			(hide yes)
			(effects
				(font
					(size 1 1)
					(thickness 0.15)
				)
				(justify mirror)
			)
		)
		(property "Author" "Antmicro"
			(at 0 0 180)
			(unlocked yes)
			(layer "B.Fab")
			(hide yes)
			(effects
				(font
					(size 1 1)
					(thickness 0.15)
				)
				(justify mirror)
			)
		)
		(property "Tolerance" "1%"
			(at 0 0 180)
			(unlocked yes)
			(layer "B.Fab")
			(hide yes)
			(effects
				(font
					(size 1 1)
					(thickness 0.15)
				)
				(justify mirror)
			)
		)
		(sheetname "/Supply/")
		(sheetfile "supply.kicad_sch")
		(attr smd)
		(fp_rect
			(start -0.925 0.47)
			(end 0.925 -0.47)
			(stroke
				(width 0.05)
				(type default)
			)
			(fill no)
			(layer "B.CrtYd")
		)
		(fp_rect
			(start -0.5 0.25)
			(end 0.5 -0.25)
			(stroke
				(width 0.15)
				(type solid)
			)
			(fill no)
			(layer "B.Fab")
		)
		(fp_text user "${REFERENCE}"
			(at -0.95 -3.168 0)
			(layer "B.Fab")
			(effects
				(font
					(size 0.7 0.7)
					(thickness 0.15)
				)
				(justify left bottom mirror)
			)
		)
		(fp_text user "License: Apache-2.0"
			(at -0.95 -5.169 0)
			(layer "B.Fab")
			(effects
				(font
					(size 0.7 0.7)
					(thickness 0.15)
				)
				(justify left bottom mirror)
			)
		)
		(fp_text user "Author: Antmicro"
			(at -0.95 -4.169 0)
			(layer "B.Fab")
			(effects
				(font
					(size 0.7 0.7)
					(thickness 0.15)
				)
				(justify left bottom mirror)
			)
		)
		(pad "1" smd roundrect
			(at -0.48 0 180)
			(size 0.59 0.64)
			(layers "B.Cu" "B.Mask" "B.Paste")
			(roundrect_rratio 0.25)
			(net 3 "GND")
			(pintype "passive")
		)
		(pad "2" smd roundrect
			(at 0.48 0 180)
			(size 0.59 0.64)
			(layers "B.Cu" "B.Mask" "B.Paste")
			(roundrect_rratio 0.25)
			(net 351 "/Supply/EN_5V")
			(pintype "passive")
		)
	)
	(footprint "antmicro-footprints:TSOT23-6"
		(layer "B.Cu")
		(at 110.267962 133.5865 90)
		(property "Reference" "U301"
			(at 2.25 -1.555 0)
			(layer "B.SilkS")
			(effects
				(font
					(size 0.7 0.7)
					(thickness 0.15)
				)
				(justify right bottom mirror)
			)
		)
		(property "Value" "AP62301_TSOT"
			(at 0 -2.6 90)
			(layer "B.Fab")
			(effects
				(font
					(size 0.7 0.7)
					(thickness 0.15)
				)
				(justify right bottom mirror)
			)
		)
		(property "Datasheet" "https://www.diodes.com/assets/Datasheets/AP62300_AP62301_AP62300T.pdf"
			(at 0 0 90)
			(layer "B.Fab")
			(hide yes)
			(effects
				(font
					(size 1.27 1.27)
					(thickness 0.15)
				)
			)
		)
		(property "MPN" "AP62301WU-7"
			(at 0 0 90)
			(unlocked yes)
			(layer "B.Fab")
			(hide yes)
			(effects
				(font
					(size 1 1)
					(thickness 0.15)
				)
				(justify mirror)
			)
		)
		(property "Manufacturer" "Diodes Incorporated"
			(at 0 0 90)
			(unlocked yes)
			(layer "B.Fab")
			(hide yes)
			(effects
				(font
					(size 1 1)
					(thickness 0.15)
				)
				(justify mirror)
			)
		)
		(property "Author" "Antmicro"
			(at 0 0 90)
			(unlocked yes)
			(layer "B.Fab")
			(hide yes)
			(effects
				(font
					(size 1 1)
					(thickness 0.15)
				)
				(justify mirror)
			)
		)
		(property "License" "Apache-2.0"
			(at 0 0 90)
			(unlocked yes)
			(layer "B.Fab")
			(hide yes)
			(effects
				(font
					(size 1 1)
					(thickness 0.15)
				)
				(justify mirror)
			)
		)
		(sheetname "/Supply/")
		(sheetfile "supply.kicad_sch")
		(attr smd)
		(fp_line
			(start 1 -1.55)
			(end -1 -1.55)
			(stroke
				(width 0.15)
				(type solid)
			)
			(layer "B.SilkS")
		)
		(fp_line
			(start 1 -1.55)
			(end 1 -1.4)
			(stroke
				(width 0.15)
				(type solid)
			)
			(layer "B.SilkS")
		)
		(fp_line
			(start -1 -1.55)
			(end -1 -1.4)
			(stroke
				(width 0.15)
				(type solid)
			)
			(layer "B.SilkS")
		)
		(fp_line
			(start 1 1.497)
			(end 1 1.375)
			(stroke
				(width 0.15)
				(type solid)
			)
			(layer "B.SilkS")
		)
		(fp_line
			(start 1 1.497)
			(end -1 1.5)
			(stroke
				(width 0.15)
				(type solid)
			)
			(layer "B.SilkS")
		)
		(fp_line
			(start -1 1.5)
			(end -1 1.375)
			(stroke
				(width 0.15)
				(type solid)
			)
			(layer "B.SilkS")
		)
		(fp_circle
			(center -1.44 1.5)
			(end -1.39 1.5)
			(stroke
				(width 0.15)
				(type solid)
			)
			(fill yes)
			(layer "B.SilkS")
		)
		(fp_rect
			(start 1.93 1.7)
			(end -1.93 -1.7)
			(stroke
				(width 0.05)
				(type solid)
			)
			(fill no)
			(layer "B.CrtYd")
		)
		(fp_line
			(start -0.45 1.521)
			(end -0.876 1.096)
			(stroke
				(width 0.15)
				(type solid)
			)
			(layer "B.Fab")
		)
		(fp_rect
			(start 0.875 -1.528)
			(end -0.875 1.525)
			(stroke
				(width 0.15)
				(type solid)
			)
			(fill no)
			(layer "B.Fab")
		)
		(fp_text user "Author: Antmicro"
			(at -1.93 -5 270)
			(layer "B.Fab")
			(effects
				(font
					(size 0.7 0.7)
					(thickness 0.15)
				)
				(justify left bottom mirror)
			)
		)
		(fp_text user "${REFERENCE}"
			(at -1.93 -3.8 270)
			(layer "B.Fab")
			(effects
				(font
					(size 0.7 0.7)
					(thickness 0.15)
				)
				(justify left bottom mirror)
			)
		)
		(fp_text user "License: Apache-2.0"
			(at -1.93 -6.199 270)
			(layer "B.Fab")
			(effects
				(font
					(size 0.7 0.7)
					(thickness 0.15)
				)
				(justify left bottom mirror)
			)
		)
		(pad "1" smd rect
			(at -1.301 0.947 180)
			(size 0.7 1.2)
			(layers "B.Cu" "B.Mask" "B.Paste")
			(net 3 "GND")
			(pinfunction "GND")
			(pintype "power_in")
		)
		(pad "2" smd rect
			(at -1.301 -0.004 180)
			(size 0.7 1.2)
			(layers "B.Cu" "B.Mask" "B.Paste")
			(net 45 "/Supply/SW_M2")
			(pinfunction "SW")
			(pintype "power_out")
		)
		(pad "3" smd rect
			(at -1.301 -0.954 180)
			(size 0.7 1.2)
			(layers "B.Cu" "B.Mask" "B.Paste")
			(net 43 "VCC")
			(pinfunction "VIN")
			(pintype "power_in")
		)
		(pad "4" smd rect
			(at 1.299 -0.954 180)
			(size 0.7 1.2)
			(layers "B.Cu" "B.Mask" "B.Paste")
			(net 354 "/Supply/FB_M2")
			(pinfunction "FB")
			(pintype "input")
		)
		(pad "5" smd rect
			(at 1.299 -0.004 180)
			(size 0.7 1.2)
			(layers "B.Cu" "B.Mask" "B.Paste")
			(net 380 "/Compute module/NVMe_EN")
			(pinfunction "EN")
			(pintype "input")
		)
		(pad "6" smd rect
			(at 1.299 0.947 180)
			(size 0.7 1.2)
			(layers "B.Cu" "B.Mask" "B.Paste")
			(net 48 "Net-(U301-BST)")
			(pinfunction "BST")
			(pintype "output")
		)
	)
	(footprint "antmicro-footprints:R_0402_1005Metric"
		(layer "B.Cu")
		(at 107.127962 133.0415 90)
		(descr "Resistor SMD 0402")
		(tags "resistor SMD 0402")
		(property "Reference" "R319"
			(at 0.825 0.32 90)
			(layer "B.SilkS")
			(effects
				(font
					(size 0.7 0.7)
					(thickness 0.15)
				)
				(justify right bottom mirror)
			)
		)
		(property "Value" "R_2k2_0402"
			(at -1.011843 -1.772047 90)
			(layer "B.Fab")
			(effects
				(font
					(size 0.7 0.7)
					(thickness 0.15)
				)
				(justify right bottom mirror)
			)
		)
		(property "Datasheet" "https://www.bourns.com/docs/product-datasheets/cr.pdf"
			(at 0 0 90)
			(layer "B.Fab")
			(hide yes)
			(effects
				(font
					(size 1.27 1.27)
					(thickness 0.15)
				)
			)
		)
		(property "MPN" "CR0402-FX-2201GLF"
			(at 0 0 90)
			(unlocked yes)
			(layer "B.Fab")
			(hide yes)
			(effects
				(font
					(size 1 1)
					(thickness 0.15)
				)
				(justify mirror)
			)
		)
		(property "Manufacturer" "Bourns"
			(at 0 0 90)
			(unlocked yes)
			(layer "B.Fab")
			(hide yes)
			(effects
				(font
					(size 1 1)
					(thickness 0.15)
				)
				(justify mirror)
			)
		)
		(property "License" "Apache-2.0"
			(at 0 0 90)
			(unlocked yes)
			(layer "B.Fab")
			(hide yes)
			(effects
				(font
					(size 1 1)
					(thickness 0.15)
				)
				(justify mirror)
			)
		)
		(property "Author" "Antmicro"
			(at 0 0 90)
			(unlocked yes)
			(layer "B.Fab")
			(hide yes)
			(effects
				(font
					(size 1 1)
					(thickness 0.15)
				)
				(justify mirror)
			)
		)
		(property "Val" "2k2"
			(at 0 0 90)
			(unlocked yes)
			(layer "B.Fab")
			(hide yes)
			(effects
				(font
					(size 1 1)
					(thickness 0.15)
				)
				(justify mirror)
			)
		)
		(property "Tolerance" "1%"
			(at 0 0 90)
			(unlocked yes)
			(layer "B.Fab")
			(hide yes)
			(effects
				(font
					(size 1 1)
					(thickness 0.15)
				)
				(justify mirror)
			)
		)
		(sheetname "/Supply/")
		(sheetfile "supply.kicad_sch")
		(attr smd)
		(fp_rect
			(start -0.925 0.47)
			(end 0.925 -0.47)
			(stroke
				(width 0.05)
				(type default)
			)
			(fill no)
			(layer "B.CrtYd")
		)
		(fp_rect
			(start -0.5 0.25)
			(end 0.5 -0.25)
			(stroke
				(width 0.15)
				(type solid)
			)
			(fill no)
			(layer "B.Fab")
		)
		(fp_text user "Author: Antmicro"
			(at -0.95 -4.169 270)
			(layer "B.Fab")
			(effects
				(font
					(size 0.7 0.7)
					(thickness 0.15)
				)
				(justify left bottom mirror)
			)
		)
		(fp_text user "${REFERENCE}"
			(at -0.95 -3.168 270)
			(layer "B.Fab")
			(effects
				(font
					(size 0.7 0.7)
					(thickness 0.15)
				)
				(justify left bottom mirror)
			)
		)
		(fp_text user "License: Apache-2.0"
			(at -0.95 -5.169 270)
			(layer "B.Fab")
			(effects
				(font
					(size 0.7 0.7)
					(thickness 0.15)
				)
				(justify left bottom mirror)
			)
		)
		(pad "1" smd roundrect
			(at -0.48 0 90)
			(size 0.59 0.64)
			(layers "B.Cu" "B.Mask" "B.Paste")
			(roundrect_rratio 0.25)
			(net 3 "GND")
			(pintype "passive")
		)
		(pad "2" smd roundrect
			(at 0.48 0 90)
			(size 0.59 0.64)
			(layers "B.Cu" "B.Mask" "B.Paste")
			(roundrect_rratio 0.25)
			(net 354 "/Supply/FB_M2")
			(pintype "passive")
		)
	)
)
